(kicad_pcb
	(version 20260206)
	(generator "pcbnew")
	(generator_version "10.0")
	(general
		(thickness 1.6)
		(legacy_teardrops no)
	)
	(paper "A4")
	(title_block
		(title "Bryce Canyon_IOM_M2_16342-2_OCP.brd")
		(comment 1 "Bryce Canyon / footprints 342-348 of 1146")
	)
	(layers
		(0 "F.Cu" signal "TOP")
		(4 "In1.Cu" signal "L2GND")
		(6 "In2.Cu" signal "L3")
		(8 "In3.Cu" signal "L4VCC")
		(10 "In4.Cu" signal "L5VCC")
		(12 "In5.Cu" signal "L6")
		(14 "In6.Cu" signal "L7GND")
		(2 "B.Cu" signal "BOTTOM")
		(9 "F.Adhes" user "F.Adhesive")
		(11 "B.Adhes" user "B.Adhesive")
		(13 "F.Paste" user "Package Geometry/Pastemask Top")
		(15 "B.Paste" user "Package Geometry/Pastemask Bottom")
		(5 "F.SilkS" user "Ref Des/Silkscreen Top")
		(7 "B.SilkS" user "Ref Des/Silkscreen Bottom")
		(1 "F.Mask" user "Board Geometry/Soldermask Top")
		(3 "B.Mask" user "Board Geometry/Soldermask Bottom")
		(17 "Dwgs.User" user "User.Drawings")
		(19 "Cmts.User" user "User.Comments")
		(21 "Eco1.User" user "User.Eco1")
		(23 "Eco2.User" user "User.Eco2")
		(25 "Edge.Cuts" user "Board Geometry/Outline")
		(27 "Margin" user)
		(31 "F.CrtYd" user "Package Geometry/Place Bound Top")
		(29 "B.CrtYd" user "Package Geometry/Place Bound Bottom")
		(35 "F.Fab" user "Ref Des/Assembly Top")
		(33 "B.Fab" user "Ref Des/Assembly Bottom")
	)
	(footprint ""
		(layer "F.Cu")
		(at 67.948556 -137.74039)
		(property "Reference" "R59"
			(at 0 0 0)
			(layer "F.SilkS")
			(hide yes)
			(effects
				(font
					(size 1.27 1.27)
				)
			)
		)
		(property "Value" "33R2F-3-GP"
			(at 0.064008 -3.993896 0)
			(unlocked yes)
			(layer "F.Fab")
			(hide yes)
			(effects
				(font
					(size 1.016 1.016)
					(thickness 0.1524)
				)
			)
		)
		(property "Device Type" "R402H16"
			(at 0.064008 -5.517896 0)
			(unlocked yes)
			(layer "F.Fab")
			(hide yes)
			(effects
				(font
					(size 1.016 1.016)
					(thickness 0.1524)
				)
			)
		)
		(duplicate_pad_numbers_are_jumpers no)
		(fp_line
			(start -0.508 -0.9398)
			(end -0.508 0.9398)
			(stroke
				(width 0.1524)
				(type default)
			)
			(layer "F.SilkS")
		)
		(fp_line
			(start 0.508 -0.9398)
			(end -0.508 -0.9398)
			(stroke
				(width 0.1524)
				(type default)
			)
			(layer "F.SilkS")
		)
		(fp_rect
			(start -0.508 0.9398)
			(end 0.508 -0.9398)
			(stroke
				(width 0)
				(type default)
			)
			(fill no)
			(layer "F.CrtYd")
		)
		(fp_rect
			(start -0.508 0.9398)
			(end 0.508 -0.9398)
			(stroke
				(width 0)
				(type default)
			)
			(fill no)
			(layer "F.Fab")
		)
		(pad "1" smd custom
			(at 0 -0.4445)
			(size 0.1397 0.1397)
			(layers "F.Cu" "F.Mask" "F.Paste")
			(net "FP_RETBTN")
			(options
				(clearance outline)
				(anchor circle)
			)
			(primitives
				(gr_poly
					(pts
						(arc
							(start -0.1778 -0.2794)
							(mid -0.249642 -0.249642)
							(end -0.2794 -0.1778)
						)
						(arc
							(start -0.2794 0.1778)
							(mid -0.249642 0.249642)
							(end -0.1778 0.2794)
						)
						(arc
							(start 0.1778 0.2794)
							(mid 0.249642 0.249642)
							(end 0.2794 0.1778)
						)
						(arc
							(start 0.2794 -0.1778)
							(mid 0.249642 -0.249642)
							(end 0.1778 -0.2794)
						)
					)
					(width 0)
					(fill yes)
				)
			)
		)
		(pad "2" smd custom
			(at 0 0.4445)
			(size 0.1397 0.1397)
			(layers "F.Cu" "F.Mask" "F.Paste")
			(net "RSTBTN_OUT_N")
			(options
				(clearance outline)
				(anchor circle)
			)
			(primitives
				(gr_poly
					(pts
						(arc
							(start -0.1778 -0.2794)
							(mid -0.249642 -0.249642)
							(end -0.2794 -0.1778)
						)
						(arc
							(start -0.2794 0.1778)
							(mid -0.249642 0.249642)
							(end -0.1778 0.2794)
						)
						(arc
							(start 0.1778 0.2794)
							(mid 0.249642 0.249642)
							(end 0.2794 0.1778)
						)
						(arc
							(start 0.2794 -0.1778)
							(mid 0.249642 -0.249642)
							(end 0.1778 -0.2794)
						)
					)
					(width 0)
					(fill yes)
				)
			)
		)
	)
	(footprint ""
		(layer "F.Cu")
		(at 72.22998 -165.619176 90)
		(property "Reference" "R542"
			(at 0 0 90)
			(layer "F.SilkS")
			(hide yes)
			(effects
				(font
					(size 1.27 1.27)
				)
			)
		)
		(property "Value" "0R2J-2-GP"
			(at 0.064008 -3.993896 90)
			(unlocked yes)
			(layer "F.Fab")
			(hide yes)
			(effects
				(font
					(size 1.016 1.016)
					(thickness 0.1524)
				)
			)
		)
		(property "Device Type" "R402H16"
			(at 0.064008 -5.517896 90)
			(unlocked yes)
			(layer "F.Fab")
			(hide yes)
			(effects
				(font
					(size 1.016 1.016)
					(thickness 0.1524)
				)
			)
		)
		(duplicate_pad_numbers_are_jumpers no)
		(fp_line
			(start 0.508 -0.9398)
			(end -0.508 -0.9398)
			(stroke
				(width 0.1524)
				(type default)
			)
			(layer "F.SilkS")
		)
		(fp_line
			(start -0.508 -0.9398)
			(end -0.508 0.9398)
			(stroke
				(width 0.1524)
				(type default)
			)
			(layer "F.SilkS")
		)
		(fp_rect
			(start -0.508 0.9398)
			(end 0.508 -0.9398)
			(stroke
				(width 0)
				(type default)
			)
			(fill no)
			(layer "F.CrtYd")
		)
		(fp_rect
			(start -0.508 0.9398)
			(end 0.508 -0.9398)
			(stroke
				(width 0)
				(type default)
			)
			(fill no)
			(layer "F.Fab")
		)
		(pad "1" smd custom
			(at 0 -0.4445 90)
			(size 0.1397 0.1397)
			(layers "F.Cu" "F.Mask" "F.Paste")
			(net "PWRGD_P1V2_STBY")
			(options
				(clearance outline)
				(anchor circle)
			)
			(primitives
				(gr_poly
					(pts
						(arc
							(start -0.1778 -0.2794)
							(mid -0.249642 -0.249642)
							(end -0.2794 -0.1778)
						)
						(arc
							(start -0.2794 0.1778)
							(mid -0.249642 0.249642)
							(end -0.1778 0.2794)
						)
						(arc
							(start 0.1778 0.2794)
							(mid 0.249642 0.249642)
							(end 0.2794 0.1778)
						)
						(arc
							(start 0.2794 -0.1778)
							(mid 0.249642 -0.249642)
							(end 0.1778 -0.2794)
						)
					)
					(width 0)
					(fill yes)
				)
			)
		)
		(pad "2" smd custom
			(at 0 0.4445 90)
			(size 0.1397 0.1397)
			(layers "F.Cu" "F.Mask" "F.Paste")
			(net "TPS74801_P1V15_STBY_EN")
			(options
				(clearance outline)
				(anchor circle)
			)
			(primitives
				(gr_poly
					(pts
						(arc
							(start -0.1778 -0.2794)
							(mid -0.249642 -0.249642)
							(end -0.2794 -0.1778)
						)
						(arc
							(start -0.2794 0.1778)
							(mid -0.249642 0.249642)
							(end -0.1778 0.2794)
						)
						(arc
							(start 0.1778 0.2794)
							(mid 0.249642 0.249642)
							(end 0.2794 0.1778)
						)
						(arc
							(start 0.2794 -0.1778)
							(mid 0.249642 -0.249642)
							(end 0.1778 -0.2794)
						)
					)
					(width 0)
					(fill yes)
				)
			)
		)
	)
	(footprint ""
		(layer "F.Cu")
		(at 174.25797 -138.239246 -135)
		(property "Reference" "VIA63"
			(at 0 0 225)
			(layer "F.SilkS")
			(hide yes)
			(effects
				(font
					(size 1.27 1.27)
				)
			)
		)
		(property "Value" "85OHM-8L-1D6MM-L16L18-GP"
			(at 4.064105 0.609655 225)
			(unlocked yes)
			(layer "F.Fab")
			(hide yes)
			(effects
				(font
					(size 1.016 1.016)
					(thickness 0.1524)
				)
			)
		)
		(property "Device Type" "VIA-PCIE-4P-368076"
			(at 4.064105 -0.914474 225)
			(unlocked yes)
			(layer "F.Fab")
			(hide yes)
			(effects
				(font
					(size 1.016 1.016)
					(thickness 0.1524)
				)
			)
		)
		(duplicate_pad_numbers_are_jumpers no)
		(fp_poly
			(pts
				(xy -1.841491 -0.381057) (xy 1.841509 -0.381058) (xy 1.841508 0.380942) (xy -1.841491 0.380942)
			)
			(stroke
				(width 0)
				(type default)
			)
			(fill no)
			(layer "F.CrtYd")
		)
		(fp_poly
			(pts
				(xy -1.841491 -0.381057) (xy 1.841509 -0.381058) (xy 1.841508 0.380942) (xy -1.841491 0.380942)
			)
			(stroke
				(width 0)
				(type default)
			)
			(fill no)
			(layer "F.Fab")
		)
		(pad "1" thru_hole circle
			(at -1.460499 0 225)
			(size 0.508 0.508)
			(drill 0.254)
			(layers "*.Cu" "*.Mask")
			(remove_unused_layers no)
			(net "GND")
			(clearance 0.127)
			(thermal_gap 0.127)
		)
		(pad "2" thru_hole circle
			(at -0.4445 0 225)
			(size 0.508 0.508)
			(drill 0.254)
			(layers "*.Cu" "*.Mask")
			(remove_unused_layers no)
			(net "PCIE_IOM_TO_COMP_14_DP")
			(clearance 0.127)
			(thermal_gap 0.127)
		)
		(pad "3" thru_hole circle
			(at 0.4445 0 225)
			(size 0.508 0.508)
			(drill 0.254)
			(layers "*.Cu" "*.Mask")
			(remove_unused_layers no)
			(net "PCIE_IOM_TO_COMP_14_DN")
			(clearance 0.127)
			(thermal_gap 0.127)
		)
		(pad "4" thru_hole circle
			(at 1.460499 0 225)
			(size 0.508 0.508)
			(drill 0.254)
			(layers "*.Cu" "*.Mask")
			(remove_unused_layers no)
			(net "GND")
			(clearance 0.127)
			(thermal_gap 0.127)
		)
	)
	(footprint ""
		(layer "F.Cu")
		(at 84.900262 -146.519646 -90)
		(property "Reference" "R129"
			(at 0 0 270)
			(layer "F.SilkS")
			(hide yes)
			(effects
				(font
					(size 1.27 1.27)
				)
			)
		)
		(property "Value" "0R2J-2-GP"
			(at 0.064008 -3.993896 270)
			(unlocked yes)
			(layer "F.Fab")
			(hide yes)
			(effects
				(font
					(size 1.016 1.016)
					(thickness 0.1524)
				)
			)
		)
		(property "Device Type" "R402H16"
			(at 0.064008 -5.517896 270)
			(unlocked yes)
			(layer "F.Fab")
			(hide yes)
			(effects
				(font
					(size 1.016 1.016)
					(thickness 0.1524)
				)
			)
		)
		(duplicate_pad_numbers_are_jumpers no)
		(fp_line
			(start -0.508 -0.9398)
			(end -0.508 0.9398)
			(stroke
				(width 0.1524)
				(type default)
			)
			(layer "F.SilkS")
		)
		(fp_line
			(start 0.508 -0.9398)
			(end -0.508 -0.9398)
			(stroke
				(width 0.1524)
				(type default)
			)
			(layer "F.SilkS")
		)
		(fp_rect
			(start -0.508 0.9398)
			(end 0.508 -0.9398)
			(stroke
				(width 0)
				(type default)
			)
			(fill no)
			(layer "F.CrtYd")
		)
		(fp_rect
			(start -0.508 0.9398)
			(end 0.508 -0.9398)
			(stroke
				(width 0)
				(type default)
			)
			(fill no)
			(layer "F.Fab")
		)
		(pad "1" smd custom
			(at 0 -0.4445 270)
			(size 0.1397 0.1397)
			(layers "F.Cu" "F.Mask" "F.Paste")
			(net "I2C_EXP_RMT_SCL")
			(options
				(clearance outline)
				(anchor circle)
			)
			(primitives
				(gr_poly
					(pts
						(arc
							(start -0.1778 -0.2794)
							(mid -0.249642 -0.249642)
							(end -0.2794 -0.1778)
						)
						(arc
							(start -0.2794 0.1778)
							(mid -0.249642 0.249642)
							(end -0.1778 0.2794)
						)
						(arc
							(start 0.1778 0.2794)
							(mid 0.249642 0.249642)
							(end 0.2794 0.1778)
						)
						(arc
							(start 0.2794 -0.1778)
							(mid 0.249642 -0.249642)
							(end 0.1778 -0.2794)
						)
					)
					(width 0)
					(fill yes)
				)
			)
		)
		(pad "2" smd custom
			(at 0 0.4445 270)
			(size 0.1397 0.1397)
			(layers "F.Cu" "F.Mask" "F.Paste")
			(net "I2C_EXP_RMT_SCL_R")
			(options
				(clearance outline)
				(anchor circle)
			)
			(primitives
				(gr_poly
					(pts
						(arc
							(start -0.1778 -0.2794)
							(mid -0.249642 -0.249642)
							(end -0.2794 -0.1778)
						)
						(arc
							(start -0.2794 0.1778)
							(mid -0.249642 0.249642)
							(end -0.1778 0.2794)
						)
						(arc
							(start 0.1778 0.2794)
							(mid 0.249642 0.249642)
							(end 0.2794 0.1778)
						)
						(arc
							(start 0.2794 -0.1778)
							(mid 0.249642 -0.249642)
							(end 0.1778 -0.2794)
						)
					)
					(width 0)
					(fill yes)
				)
			)
		)
	)
	(footprint ""
		(layer "F.Cu")
		(at 34.03473 -156.807916 -90)
		(property "Reference" "R320"
			(at 0 0 270)
			(layer "F.SilkS")
			(hide yes)
			(effects
				(font
					(size 1.27 1.27)
				)
			)
		)
		(property "Value" "0R2J-2-GP"
			(at 0.064008 -3.993896 270)
			(unlocked yes)
			(layer "F.Fab")
			(hide yes)
			(effects
				(font
					(size 1.016 1.016)
					(thickness 0.1524)
				)
			)
		)
		(property "Device Type" "R402H16"
			(at 0.064008 -5.517896 270)
			(unlocked yes)
			(layer "F.Fab")
			(hide yes)
			(effects
				(font
					(size 1.016 1.016)
					(thickness 0.1524)
				)
			)
		)
		(duplicate_pad_numbers_are_jumpers no)
		(fp_line
			(start -0.508 -0.9398)
			(end -0.508 0.9398)
			(stroke
				(width 0.1524)
				(type default)
			)
			(layer "F.SilkS")
		)
		(fp_line
			(start 0.508 -0.9398)
			(end -0.508 -0.9398)
			(stroke
				(width 0.1524)
				(type default)
			)
			(layer "F.SilkS")
		)
		(fp_rect
			(start -0.508 0.9398)
			(end 0.508 -0.9398)
			(stroke
				(width 0)
				(type default)
			)
			(fill no)
			(layer "F.CrtYd")
		)
		(fp_rect
			(start -0.508 0.9398)
			(end 0.508 -0.9398)
			(stroke
				(width 0)
				(type default)
			)
			(fill no)
			(layer "F.Fab")
		)
		(pad "1" smd custom
			(at 0 -0.4445 270)
			(size 0.1397 0.1397)
			(layers "F.Cu" "F.Mask" "F.Paste")
			(net "SCC_A_HB_IN_R")
			(options
				(clearance outline)
				(anchor circle)
			)
			(primitives
				(gr_poly
					(pts
						(arc
							(start -0.1778 -0.2794)
							(mid -0.249642 -0.249642)
							(end -0.2794 -0.1778)
						)
						(arc
							(start -0.2794 0.1778)
							(mid -0.249642 0.249642)
							(end -0.1778 0.2794)
						)
						(arc
							(start 0.1778 0.2794)
							(mid 0.249642 0.249642)
							(end 0.2794 0.1778)
						)
						(arc
							(start 0.2794 -0.1778)
							(mid 0.249642 -0.249642)
							(end 0.1778 -0.2794)
						)
					)
					(width 0)
					(fill yes)
				)
			)
		)
		(pad "2" smd custom
			(at 0 0.4445 270)
			(size 0.1397 0.1397)
			(layers "F.Cu" "F.Mask" "F.Paste")
			(net "SCC_LOC_HEARTBEAT")
			(options
				(clearance outline)
				(anchor circle)
			)
			(primitives
				(gr_poly
					(pts
						(arc
							(start -0.1778 -0.2794)
							(mid -0.249642 -0.249642)
							(end -0.2794 -0.1778)
						)
						(arc
							(start -0.2794 0.1778)
							(mid -0.249642 0.249642)
							(end -0.1778 0.2794)
						)
						(arc
							(start 0.1778 0.2794)
							(mid 0.249642 0.249642)
							(end 0.2794 0.1778)
						)
						(arc
							(start 0.2794 -0.1778)
							(mid 0.249642 -0.249642)
							(end 0.1778 -0.2794)
						)
					)
					(width 0)
					(fill yes)
				)
			)
		)
	)
	(footprint ""
		(layer "F.Cu")
		(at 87.930228 -67.507612 -90)
		(property "Reference" "R14"
			(at 0 0 270)
			(layer "F.SilkS")
			(hide yes)
			(effects
				(font
					(size 1.27 1.27)
				)
			)
		)
		(property "Value" "0R2J-2-GP"
			(at 0.064008 -3.993896 270)
			(unlocked yes)
			(layer "F.Fab")
			(hide yes)
			(effects
				(font
					(size 1.016 1.016)
					(thickness 0.1524)
				)
			)
		)
		(property "Device Type" "R402H16"
			(at 0.064008 -5.517896 270)
			(unlocked yes)
			(layer "F.Fab")
			(hide yes)
			(effects
				(font
					(size 1.016 1.016)
					(thickness 0.1524)
				)
			)
		)
		(duplicate_pad_numbers_are_jumpers no)
		(fp_line
			(start -0.508 -0.9398)
			(end -0.508 0.9398)
			(stroke
				(width 0.1524)
				(type default)
			)
			(layer "F.SilkS")
		)
		(fp_line
			(start 0.508 -0.9398)
			(end -0.508 -0.9398)
			(stroke
				(width 0.1524)
				(type default)
			)
			(layer "F.SilkS")
		)
		(fp_rect
			(start -0.508 0.9398)
			(end 0.508 -0.9398)
			(stroke
				(width 0)
				(type default)
			)
			(fill no)
			(layer "F.CrtYd")
		)
		(fp_rect
			(start -0.508 0.9398)
			(end 0.508 -0.9398)
			(stroke
				(width 0)
				(type default)
			)
			(fill no)
			(layer "F.Fab")
		)
		(pad "1" smd custom
			(at 0 -0.4445 270)
			(size 0.1397 0.1397)
			(layers "F.Cu" "F.Mask" "F.Paste")
			(net "NCSI_RXD0")
			(options
				(clearance outline)
				(anchor circle)
			)
			(primitives
				(gr_poly
					(pts
						(arc
							(start -0.1778 -0.2794)
							(mid -0.249642 -0.249642)
							(end -0.2794 -0.1778)
						)
						(arc
							(start -0.2794 0.1778)
							(mid -0.249642 0.249642)
							(end -0.1778 0.2794)
						)
						(arc
							(start 0.1778 0.2794)
							(mid 0.249642 0.249642)
							(end 0.2794 0.1778)
						)
						(arc
							(start 0.2794 -0.1778)
							(mid 0.249642 -0.249642)
							(end 0.1778 -0.2794)
						)
					)
					(width 0)
					(fill yes)
				)
			)
		)
		(pad "2" smd custom
			(at 0 0.4445 270)
			(size 0.1397 0.1397)
			(layers "F.Cu" "F.Mask" "F.Paste")
			(net "NCSI_RXD0_R")
			(options
				(clearance outline)
				(anchor circle)
			)
			(primitives
				(gr_poly
					(pts
						(arc
							(start -0.1778 -0.2794)
							(mid -0.249642 -0.249642)
							(end -0.2794 -0.1778)
						)
						(arc
							(start -0.2794 0.1778)
							(mid -0.249642 0.249642)
							(end -0.1778 0.2794)
						)
						(arc
							(start 0.1778 0.2794)
							(mid 0.249642 0.249642)
							(end 0.2794 0.1778)
						)
						(arc
							(start 0.2794 -0.1778)
							(mid 0.249642 -0.249642)
							(end 0.1778 -0.2794)
						)
					)
					(width 0)
					(fill yes)
				)
			)
		)
	)
	(footprint ""
		(layer "F.Cu")
		(at 89.45372 -162.360356 180)
		(property "Reference" "C19"
			(at 0 0 180)
			(layer "F.SilkS")
			(hide yes)
			(effects
				(font
					(size 1.27 1.27)
				)
			)
		)
		(property "Value" "SC1U16V3KX-5GP"
			(at 0 -2.8194 180)
			(unlocked yes)
			(layer "F.Fab")
			(hide yes)
			(effects
				(font
					(size 1.016 1.016)
					(thickness 0.1524)
				)
			)
		)
		(property "Device Type" "C603H36"
			(at 0 -4.3434 180)
			(unlocked yes)
			(layer "F.Fab")
			(hide yes)
			(effects
				(font
					(size 1.016 1.016)
					(thickness 0.1524)
				)
			)
		)
		(duplicate_pad_numbers_are_jumpers no)
		(fp_line
			(start 0.508 0)
			(end -0.508 0)
			(stroke
				(width 0.2032)
				(type default)
			)
			(layer "F.SilkS")
		)
		(fp_rect
			(start -0.5842 1.3335)
			(end 0.5842 -1.3335)
			(stroke
				(width 0)
				(type default)
			)
			(fill no)
			(layer "F.CrtYd")
		)
		(fp_rect
			(start -0.5842 1.3335)
			(end 0.5842 -1.3335)
			(stroke
				(width 0)
				(type default)
			)
			(fill no)
			(layer "F.Fab")
		)
		(pad "1" smd custom
			(at 0 -0.762 180)
			(size 0.2159 0.2159)
			(layers "F.Cu" "F.Mask" "F.Paste")
			(net "PLLFILT")
			(options
				(clearance outline)
				(anchor circle)
			)
			(primitives
				(gr_poly
					(pts
						(arc
							(start -0.3302 -0.4318)
							(mid -0.402042 -0.402042)
							(end -0.4318 -0.3302)
						)
						(arc
							(start -0.4318 0.3302)
							(mid -0.402042 0.402042)
							(end -0.3302 0.4318)
						)
						(arc
							(start 0.3302 0.4318)
							(mid 0.402042 0.402042)
							(end 0.4318 0.3302)
						)
						(arc
							(start 0.4318 -0.3302)
							(mid 0.402042 -0.402042)
							(end 0.3302 -0.4318)
						)
					)
					(width 0)
					(fill yes)
				)
			)
		)
		(pad "2" smd custom
			(at 0 0.762 180)
			(size 0.2159 0.2159)
			(layers "F.Cu" "F.Mask" "F.Paste")
			(net "GND")
			(options
				(clearance outline)
				(anchor circle)
			)
			(primitives
				(gr_poly
					(pts
						(arc
							(start -0.3302 -0.4318)
							(mid -0.402042 -0.402042)
							(end -0.4318 -0.3302)
						)
						(arc
							(start -0.4318 0.3302)
							(mid -0.402042 0.402042)
							(end -0.3302 0.4318)
						)
						(arc
							(start 0.3302 0.4318)
							(mid 0.402042 0.402042)
							(end 0.4318 0.3302)
						)
						(arc
							(start 0.4318 -0.3302)
							(mid 0.402042 -0.402042)
							(end 0.3302 -0.4318)
						)
					)
					(width 0)
					(fill yes)
				)
			)
		)
	)
)
